(kicad_pcb
	(version 20260206)
	(generator "pcbnew")
	(generator_version "10.0")
	(general
		(thickness 1.6)
		(legacy_teardrops no)
	)
	(paper "A4")
	(title_block
		(title "Wiwynn_Tioga_Pass_MB.brd")
		(comment 1 "Tioga Pass / footprints 1292-1296 of 4770")
	)
	(layers
		(0 "F.Cu" signal "TOP")
		(4 "In1.Cu" signal "L2GND")
		(6 "In2.Cu" signal "L3")
		(8 "In3.Cu" signal "L4GND")
		(10 "In4.Cu" signal "L5")
		(12 "In5.Cu" signal "L6GND")
		(14 "In6.Cu" signal "L7VCC")
		(16 "In7.Cu" signal "L8VCC")
		(18 "In8.Cu" signal "L9GND")
		(20 "In9.Cu" signal "L10")
		(22 "In10.Cu" signal "L11GND")
		(24 "In11.Cu" signal "L12")
		(26 "In12.Cu" signal "L13GND")
		(2 "B.Cu" signal "BOTTOM")
		(9 "F.Adhes" user "F.Adhesive")
		(11 "B.Adhes" user "B.Adhesive")
		(13 "F.Paste" user "Package Geometry/Pastemask Top")
		(15 "B.Paste" user "Package Geometry/Pastemask Bottom")
		(5 "F.SilkS" user "Ref Des/Silkscreen Top")
		(7 "B.SilkS" user "Ref Des/Silkscreen Bottom")
		(1 "F.Mask" user "Board Geometry/Soldermask Top")
		(3 "B.Mask" user "Board Geometry/Soldermask Bottom")
		(17 "Dwgs.User" user "User.Drawings")
		(19 "Cmts.User" user "User.Comments")
		(21 "Eco1.User" user "User.Eco1")
		(23 "Eco2.User" user "User.Eco2")
		(25 "Edge.Cuts" user "Board Geometry/Outline")
		(27 "Margin" user)
		(31 "F.CrtYd" user "Package Geometry/Place Bound Top")
		(29 "B.CrtYd" user "Package Geometry/Place Bound Bottom")
		(35 "F.Fab" user "Ref Des/Assembly Top")
		(33 "B.Fab" user "Ref Des/Assembly Bottom")
	)
	(footprint ""
		(layer "F.Cu")
		(at 467.9315 -23.0505 180)
		(property "Reference" "EU8F1"
			(at -2.56667 -0.254 90)
			(unlocked yes)
			(layer "F.SilkS")
			(effects
				(font
					(size 0.7874 0.5842)
					(thickness 0.1524)
				)
			)
		)
		(property "Value" ""
			(at 0 0 180)
			(layer "F.Fab")
			(effects
				(font
					(size 1.27 1.27)
				)
			)
		)
		(duplicate_pad_numbers_are_jumpers no)
		(fp_line
			(start 1.050036 0.834898)
			(end 1.050036 1.050036)
			(stroke
				(width 0.1524)
				(type default)
			)
			(layer "F.SilkS")
		)
		(fp_line
			(start 1.050036 -0.834898)
			(end 1.050036 -1.050036)
			(stroke
				(width 0.1524)
				(type default)
			)
			(layer "F.SilkS")
		)
		(fp_line
			(start 0.834898 1.050036)
			(end 1.050036 1.050036)
			(stroke
				(width 0.1524)
				(type default)
			)
			(layer "F.SilkS")
		)
		(fp_line
			(start 0.834898 -1.050036)
			(end 1.050036 -1.050036)
			(stroke
				(width 0.1524)
				(type default)
			)
			(layer "F.SilkS")
		)
		(fp_line
			(start -0.834898 1.050036)
			(end -1.050036 1.050036)
			(stroke
				(width 0.1524)
				(type default)
			)
			(layer "F.SilkS")
		)
		(fp_line
			(start -0.834898 -1.050036)
			(end -1.050036 -1.050036)
			(stroke
				(width 0.1524)
				(type default)
			)
			(layer "F.SilkS")
		)
		(fp_line
			(start -1.050036 0.834898)
			(end -1.050036 1.050036)
			(stroke
				(width 0.1524)
				(type default)
			)
			(layer "F.SilkS")
		)
		(fp_line
			(start -1.050036 -0.834898)
			(end -1.050036 -1.050036)
			(stroke
				(width 0.1524)
				(type default)
			)
			(layer "F.SilkS")
		)
		(fp_circle
			(center -1.675892 -0.964438)
			(end -1.802638 -0.964438)
			(stroke
				(width 0.254)
				(type default)
			)
			(fill no)
			(layer "F.SilkS")
		)
		(fp_rect
			(start 0.4445 -0.4445)
			(end -0.4445 0.4445)
			(stroke
				(width 0)
				(type default)
			)
			(fill yes)
			(layer "F.Paste")
		)
		(fp_rect
			(start 1.050036 -1.050036)
			(end -1.050036 1.050036)
			(stroke
				(width 0)
				(type default)
			)
			(fill no)
			(layer "F.CrtYd")
		)
		(fp_line
			(start 1.050036 1.050036)
			(end -1.050036 1.050036)
			(stroke
				(width 0.1)
				(type default)
			)
			(layer "F.Fab")
		)
		(fp_line
			(start 1.050036 -1.050036)
			(end 1.050036 1.050036)
			(stroke
				(width 0.1)
				(type default)
			)
			(layer "F.Fab")
		)
		(fp_line
			(start -1.050036 1.050036)
			(end -1.050036 -1.050036)
			(stroke
				(width 0.1)
				(type default)
			)
			(layer "F.Fab")
		)
		(fp_line
			(start -1.050036 -1.050036)
			(end 1.050036 -1.050036)
			(stroke
				(width 0.1)
				(type default)
			)
			(layer "F.Fab")
		)
		(fp_circle
			(center -1.675892 -0.964438)
			(end -1.802638 -0.964438)
			(stroke
				(width 0.254)
				(type default)
			)
			(fill no)
			(layer "F.Fab")
		)
		(pad "1" smd custom
			(at -0.9779 -0.40005 180)
			(size 0.0508 0.0508)
			(layers "F.Cu" "F.Mask" "F.Paste")
			(net "VR_P3V3_STBY_LGATE")
			(options
				(clearance outline)
				(anchor circle)
			)
			(primitives
				(gr_poly
					(pts
						(xy -0.3302 0.1016) (xy -0.3302 -0.1016)
						(arc
							(start 0.2286 -0.1016)
							(mid 0.3302 0)
							(end 0.2286 0.1016)
						)
					)
					(width 0)
					(fill yes)
				)
			)
		)
		(pad "2" smd custom
			(at -0.9779 0 180)
			(size 0.0508 0.0508)
			(layers "F.Cu" "F.Mask" "F.Paste")
			(net "VR_P3V3_STBY_PHASE")
			(options
				(clearance outline)
				(anchor circle)
			)
			(primitives
				(gr_poly
					(pts
						(xy -0.3302 0.1016) (xy -0.3302 -0.1016)
						(arc
							(start 0.2286 -0.1016)
							(mid 0.3302 0)
							(end 0.2286 0.1016)
						)
					)
					(width 0)
					(fill yes)
				)
			)
		)
		(pad "3" smd custom
			(at -0.9779 0.40005 180)
			(size 0.0508 0.0508)
			(layers "F.Cu" "F.Mask" "F.Paste")
			(net "VR_P3V3_STBY_UGATE")
			(options
				(clearance outline)
				(anchor circle)
			)
			(primitives
				(gr_poly
					(pts
						(xy -0.3302 0.1016) (xy -0.3302 -0.1016)
						(arc
							(start 0.2286 -0.1016)
							(mid 0.3302 0)
							(end 0.2286 0.1016)
						)
					)
					(width 0)
					(fill yes)
				)
			)
		)
		(pad "4" smd custom
			(at -0.40005 0.9779 180)
			(size 0.0508 0.0508)
			(layers "F.Cu" "F.Mask" "F.Paste")
			(net "VR_P3V3_STBY_BOOT")
			(options
				(clearance outline)
				(anchor circle)
			)
			(primitives
				(gr_poly
					(pts
						(xy 0.1016 0.3302) (xy -0.1016 0.3302)
						(arc
							(start -0.1016 -0.2286)
							(mid 0 -0.3302)
							(end 0.1016 -0.2286)
						)
					)
					(width 0)
					(fill yes)
				)
			)
		)
		(pad "5" smd custom
			(at 0 0.9779 180)
			(size 0.0508 0.0508)
			(layers "F.Cu" "F.Mask" "F.Paste")
			(net "P5V_STBY")
			(options
				(clearance outline)
				(anchor circle)
			)
			(primitives
				(gr_poly
					(pts
						(xy 0.1016 0.3302) (xy -0.1016 0.3302)
						(arc
							(start -0.1016 -0.2286)
							(mid 0 -0.3302)
							(end 0.1016 -0.2286)
						)
					)
					(width 0)
					(fill yes)
				)
			)
		)
		(pad "6" smd custom
			(at 0.40005 0.9779 180)
			(size 0.0508 0.0508)
			(layers "F.Cu" "F.Mask" "F.Paste")
			(net "VSENSE_VOUT_P3V3_STBY")
			(options
				(clearance outline)
				(anchor circle)
			)
			(primitives
				(gr_poly
					(pts
						(xy 0.1016 0.3302) (xy -0.1016 0.3302)
						(arc
							(start -0.1016 -0.2286)
							(mid 0 -0.3302)
							(end 0.1016 -0.2286)
						)
					)
					(width 0)
					(fill yes)
				)
			)
		)
		(pad "7" smd custom
			(at 0.9779 0.40005 180)
			(size 0.0508 0.0508)
			(layers "F.Cu" "F.Mask" "F.Paste")
			(net "VSENSE_RGND_P3V3_STBY")
			(options
				(clearance outline)
				(anchor circle)
			)
			(primitives
				(gr_poly
					(pts
						(xy 0.3302 -0.1016) (xy 0.3302 0.1016)
						(arc
							(start -0.2286 0.1016)
							(mid -0.3302 0)
							(end -0.2286 -0.1016)
						)
					)
					(width 0)
					(fill yes)
				)
			)
		)
		(pad "8" smd custom
			(at 0.9779 0 180)
			(size 0.0508 0.0508)
			(layers "F.Cu" "F.Mask" "F.Paste")
			(net "VR_P3V3_STBY_EN")
			(options
				(clearance outline)
				(anchor circle)
			)
			(primitives
				(gr_poly
					(pts
						(xy 0.3302 -0.1016) (xy 0.3302 0.1016)
						(arc
							(start -0.2286 0.1016)
							(mid -0.3302 0)
							(end -0.2286 -0.1016)
						)
					)
					(width 0)
					(fill yes)
				)
			)
		)
		(pad "9" smd custom
			(at 0.9779 -0.40005 180)
			(size 0.0508 0.0508)
			(layers "F.Cu" "F.Mask" "F.Paste")
			(net "PWRGD_P3V3_STBY_R")
			(options
				(clearance outline)
				(anchor circle)
			)
			(primitives
				(gr_poly
					(pts
						(xy 0.3302 -0.1016) (xy 0.3302 0.1016)
						(arc
							(start -0.2286 0.1016)
							(mid -0.3302 0)
							(end -0.2286 -0.1016)
						)
					)
					(width 0)
					(fill yes)
				)
			)
		)
		(pad "10" smd custom
			(at 0.40005 -0.9779 180)
			(size 0.0508 0.0508)
			(layers "F.Cu" "F.Mask" "F.Paste")
			(net "VR_P3V3_STBY_OCSELECT")
			(options
				(clearance outline)
				(anchor circle)
			)
			(primitives
				(gr_poly
					(pts
						(xy -0.1016 -0.3302) (xy 0.1016 -0.3302)
						(arc
							(start 0.1016 0.2286)
							(mid 0 0.3302)
							(end -0.1016 0.2286)
						)
					)
					(width 0)
					(fill yes)
				)
			)
		)
		(pad "11" smd custom
			(at 0 -0.9779 180)
			(size 0.0508 0.0508)
			(layers "F.Cu" "F.Mask" "F.Paste")
			(net "AGND_P3V3_STBY")
			(options
				(clearance outline)
				(anchor circle)
			)
			(primitives
				(gr_poly
					(pts
						(xy -0.1016 -0.3302) (xy 0.1016 -0.3302)
						(arc
							(start 0.1016 0.2286)
							(mid 0 0.3302)
							(end -0.1016 0.2286)
						)
					)
					(width 0)
					(fill yes)
				)
			)
		)
		(pad "12" smd custom
			(at -0.40005 -0.9779 180)
			(size 0.0508 0.0508)
			(layers "F.Cu" "F.Mask" "F.Paste")
			(net "AGND_P3V3_STBY")
			(options
				(clearance outline)
				(anchor circle)
			)
			(primitives
				(gr_poly
					(pts
						(xy -0.1016 -0.3302) (xy 0.1016 -0.3302)
						(arc
							(start 0.1016 0.2286)
							(mid 0 0.3302)
							(end -0.1016 0.2286)
						)
					)
					(width 0)
					(fill yes)
				)
			)
		)
		(pad "13" smd rect
			(at 0 0 180)
			(size 0.889 0.889)
			(layers "F.Cu" "F.Mask" "F.Paste")
			(net "AGND_P3V3_STBY")
		)
	)
	(footprint ""
		(layer "F.Cu")
		(at 111.000032 -149.8092 90)
		(property "Reference" "C3A2"
			(at 1.848866 0.752348 90)
			(unlocked yes)
			(layer "F.SilkS")
			(effects
				(font
					(size 1.27 0.9652)
					(thickness 0.1524)
				)
			)
		)
		(property "Value" ""
			(at 0 0 90)
			(layer "F.Fab")
			(effects
				(font
					(size 1.27 1.27)
				)
			)
		)
		(duplicate_pad_numbers_are_jumpers no)
		(fp_rect
			(start -0.500126 1.598422)
			(end 0.500126 -0.201422)
			(stroke
				(width 0)
				(type default)
			)
			(fill no)
			(layer "F.CrtYd")
		)
		(fp_line
			(start 0.500126 -0.201422)
			(end 0.500126 1.598422)
			(stroke
				(width 0.1)
				(type default)
			)
			(layer "F.Fab")
		)
		(fp_line
			(start -0.500126 -0.201422)
			(end 0.500126 -0.201422)
			(stroke
				(width 0.1)
				(type default)
			)
			(layer "F.Fab")
		)
		(fp_line
			(start 0.500126 1.598422)
			(end -0.500126 1.598422)
			(stroke
				(width 0.1)
				(type default)
			)
			(layer "F.Fab")
		)
		(fp_line
			(start -0.500126 1.598422)
			(end -0.500126 -0.201422)
			(stroke
				(width 0.1)
				(type default)
			)
			(layer "F.Fab")
		)
		(pad "1" smd rect
			(at 0 0)
			(size 0.889 0.9906)
			(layers "F.Cu" "F.Mask" "F.Paste")
			(net "PVDDQ_KLM")
		)
		(pad "2" smd rect
			(at 0 1.397)
			(size 0.889 0.9906)
			(layers "F.Cu" "F.Mask" "F.Paste")
			(net "GND")
		)
		(zone
			(layer "F.Cu")
			(hatch none 0.5)
			(connect_pads
				(clearance 0)
			)
			(min_thickness 0.25)
			(keepout
				(tracks allowed)
				(vias not_allowed)
				(pads allowed)
				(copperpour not_allowed)
				(footprints allowed)
			)
			(placement
				(enabled no)
				(sheetname "")
			)
			(fill
				(thermal_gap 0.5)
				(thermal_bridge_width 0.5)
				(island_removal_mode 0)
			)
			(polygon
				(pts
					(xy 111.952532 -149.3139) (xy 111.952532 -150.3045) (xy 111.444532 -150.3045) (xy 111.444532 -149.3139)
				)
			)
		)
		(zone
			(layer "F.Cu")
			(hatch none 0.5)
			(connect_pads
				(clearance 0)
			)
			(min_thickness 0.25)
			(keepout
				(tracks not_allowed)
				(vias allowed)
				(pads allowed)
				(copperpour not_allowed)
				(footprints allowed)
			)
			(placement
				(enabled no)
				(sheetname "")
			)
			(fill
				(thermal_gap 0.5)
				(thermal_bridge_width 0.5)
				(island_removal_mode 0)
			)
			(polygon
				(pts
					(xy 111.952532 -149.3139) (xy 111.952532 -150.3045) (xy 111.444532 -150.3045) (xy 111.444532 -149.3139)
				)
			)
		)
	)
	(footprint ""
		(layer "F.Cu")
		(at 163.576 -83.058 -90)
		(property "Reference" "R4D13"
			(at 0 0 270)
			(layer "F.SilkS")
			(hide yes)
			(effects
				(font
					(size 1.27 1.27)
				)
			)
		)
		(property "Value" ""
			(at 0 0 270)
			(layer "F.Fab")
			(effects
				(font
					(size 1.27 1.27)
				)
			)
		)
		(duplicate_pad_numbers_are_jumpers no)
		(fp_poly
			(pts
				(xy -0.2794 -0.1016) (xy 0.2794 -0.1016) (xy 0.2794 0.9906) (xy -0.2794 0.9906)
			)
			(stroke
				(width 0)
				(type default)
			)
			(fill no)
			(layer "F.CrtYd")
		)
		(fp_line
			(start -0.2794 0.9906)
			(end 0.2794 0.9906)
			(stroke
				(width 0.1)
				(type default)
			)
			(layer "F.Fab")
		)
		(fp_line
			(start 0.2794 0.9906)
			(end 0.2794 -0.1016)
			(stroke
				(width 0.1)
				(type default)
			)
			(layer "F.Fab")
		)
		(fp_line
			(start -0.2794 -0.1016)
			(end -0.2794 0.9906)
			(stroke
				(width 0.1)
				(type default)
			)
			(layer "F.Fab")
		)
		(fp_line
			(start 0.2794 -0.1016)
			(end -0.2794 -0.1016)
			(stroke
				(width 0.1)
				(type default)
			)
			(layer "F.Fab")
		)
		(pad "1" smd rect
			(at 0 0 270)
			(size 0.508 0.508)
			(layers "F.Cu" "F.Mask" "F.Paste")
			(net "CLK_100M_CPU1_PE_REFCLK_R_DP")
		)
		(pad "2" smd rect
			(at 0 0.889 270)
			(size 0.508 0.508)
			(layers "F.Cu" "F.Mask" "F.Paste")
			(net "CLK_100M_CPU1_PE_REFCLK_DP")
		)
		(zone
			(layer "F.Cu")
			(hatch none 0.5)
			(connect_pads
				(clearance 0)
			)
			(min_thickness 0.25)
			(keepout
				(tracks not_allowed)
				(vias allowed)
				(pads allowed)
				(copperpour not_allowed)
				(footprints allowed)
			)
			(placement
				(enabled no)
				(sheetname "")
			)
			(fill
				(thermal_gap 0.5)
				(thermal_bridge_width 0.5)
				(island_removal_mode 0)
			)
			(polygon
				(pts
					(xy 162.941 -83.312) (xy 162.941 -82.804) (xy 163.322 -82.804) (xy 163.322 -83.312)
				)
			)
		)
		(zone
			(layer "F.Cu")
			(hatch none 0.5)
			(connect_pads
				(clearance 0)
			)
			(min_thickness 0.25)
			(keepout
				(tracks allowed)
				(vias not_allowed)
				(pads allowed)
				(copperpour not_allowed)
				(footprints allowed)
			)
			(placement
				(enabled no)
				(sheetname "")
			)
			(fill
				(thermal_gap 0.5)
				(thermal_bridge_width 0.5)
				(island_removal_mode 0)
			)
			(polygon
				(pts
					(xy 163.322 -83.312) (xy 163.322 -82.804) (xy 162.941 -82.804) (xy 162.941 -83.312)
				)
			)
		)
	)
	(footprint ""
		(layer "F.Cu")
		(at 188.137038 -65.27546 180)
		(property "Reference" "RF1"
			(at -0.8382 -0.67818 180)
			(unlocked yes)
			(layer "F.SilkS")
			(effects
				(font
					(size 0.4064 0.254)
					(thickness 0.1524)
				)
				(justify left)
			)
		)
		(property "Value" ""
			(at 0 0 180)
			(layer "F.Fab")
			(effects
				(font
					(size 1.27 1.27)
				)
			)
		)
		(duplicate_pad_numbers_are_jumpers no)
		(fp_poly
			(pts
				(xy -0.2794 -0.1016) (xy 0.2794 -0.1016) (xy 0.2794 0.9906) (xy -0.2794 0.9906)
			)
			(stroke
				(width 0)
				(type default)
			)
			(fill no)
			(layer "F.CrtYd")
		)
		(fp_line
			(start 0.2794 0.9906)
			(end 0.2794 -0.1016)
			(stroke
				(width 0.1)
				(type default)
			)
			(layer "F.Fab")
		)
		(fp_line
			(start 0.2794 -0.1016)
			(end -0.2794 -0.1016)
			(stroke
				(width 0.1)
				(type default)
			)
			(layer "F.Fab")
		)
		(fp_line
			(start -0.2794 0.9906)
			(end 0.2794 0.9906)
			(stroke
				(width 0.1)
				(type default)
			)
			(layer "F.Fab")
		)
		(fp_line
			(start -0.2794 -0.1016)
			(end -0.2794 0.9906)
			(stroke
				(width 0.1)
				(type default)
			)
			(layer "F.Fab")
		)
		(pad "1" smd rect
			(at 0 0 180)
			(size 0.508 0.508)
			(layers "F.Cu" "F.Mask" "F.Paste")
			(net "VR_PVCCIN_CPU0_AIREF1")
		)
		(pad "2" smd rect
			(at 0 0.889 180)
			(size 0.508 0.508)
			(layers "F.Cu" "F.Mask" "F.Paste")
			(net "ISENSE_PVCCIN_CPU0_PH1_IMON")
		)
		(zone
			(layer "F.Cu")
			(hatch none 0.5)
			(connect_pads
				(clearance 0)
			)
			(min_thickness 0.25)
			(keepout
				(tracks not_allowed)
				(vias allowed)
				(pads allowed)
				(copperpour not_allowed)
				(footprints allowed)
			)
			(placement
				(enabled no)
				(sheetname "")
			)
			(fill
				(thermal_gap 0.5)
				(thermal_bridge_width 0.5)
				(island_removal_mode 0)
			)
			(polygon
				(pts
					(xy 188.391038 -65.91046) (xy 187.883038 -65.91046) (xy 187.883038 -65.52946) (xy 188.391038 -65.52946)
				)
			)
		)
		(zone
			(layer "F.Cu")
			(hatch none 0.5)
			(connect_pads
				(clearance 0)
			)
			(min_thickness 0.25)
			(keepout
				(tracks allowed)
				(vias not_allowed)
				(pads allowed)
				(copperpour not_allowed)
				(footprints allowed)
			)
			(placement
				(enabled no)
				(sheetname "")
			)
			(fill
				(thermal_gap 0.5)
				(thermal_bridge_width 0.5)
				(island_removal_mode 0)
			)
			(polygon
				(pts
					(xy 188.391038 -65.52946) (xy 187.883038 -65.52946) (xy 187.883038 -65.91046) (xy 188.391038 -65.91046)
				)
			)
		)
	)
	(footprint ""
		(layer "F.Cu")
		(at 30.477968 -140.0556 90)
		(property "Reference" "C1A17"
			(at 0 0 90)
			(layer "F.SilkS")
			(hide yes)
			(effects
				(font
					(size 1.27 1.27)
				)
			)
		)
		(property "Value" ""
			(at 0 0 90)
			(layer "F.Fab")
			(effects
				(font
					(size 1.27 1.27)
				)
			)
		)
		(duplicate_pad_numbers_are_jumpers no)
		(fp_poly
			(pts
				(xy 0.3048 -0.1016) (xy 0.3048 0.9906) (xy -0.3048 0.9906) (xy -0.3048 -0.1016)
			)
			(stroke
				(width 0)
				(type default)
			)
			(fill no)
			(layer "F.CrtYd")
		)
		(fp_line
			(start 0.3048 -0.1016)
			(end -0.3048 -0.1016)
			(stroke
				(width 0.1)
				(type default)
			)
			(layer "F.Fab")
		)
		(fp_line
			(start -0.3048 -0.1016)
			(end -0.3048 0.9906)
			(stroke
				(width 0.1)
				(type default)
			)
			(layer "F.Fab")
		)
		(fp_line
			(start 0.3048 0.9906)
			(end 0.3048 -0.1016)
			(stroke
				(width 0.1)
				(type default)
			)
			(layer "F.Fab")
		)
		(fp_line
			(start -0.3048 0.9906)
			(end 0.3048 0.9906)
			(stroke
				(width 0.1)
				(type default)
			)
			(layer "F.Fab")
		)
		(pad "1" smd rect
			(at 0 0 90)
			(size 0.508 0.508)
			(layers "F.Cu" "F.Mask" "F.Paste")
			(net "M_L_VREF")
		)
		(pad "2" smd rect
			(at 0 0.889 90)
			(size 0.508 0.508)
			(layers "F.Cu" "F.Mask" "F.Paste")
			(net "GND")
		)
		(zone
			(layer "F.Cu")
			(hatch none 0.5)
			(connect_pads
				(clearance 0)
			)
			(min_thickness 0.25)
			(keepout
				(tracks allowed)
				(vias not_allowed)
				(pads allowed)
				(copperpour not_allowed)
				(footprints allowed)
			)
			(placement
				(enabled no)
				(sheetname "")
			)
			(fill
				(thermal_gap 0.5)
				(thermal_bridge_width 0.5)
				(island_removal_mode 0)
			)
			(polygon
				(pts
					(xy 30.731968 -139.8016) (xy 30.731968 -140.3096) (xy 31.112968 -140.3096) (xy 31.112968 -139.8016)
				)
			)
		)
		(zone
			(layer "F.Cu")
			(hatch none 0.5)
			(connect_pads
				(clearance 0)
			)
			(min_thickness 0.25)
			(keepout
				(tracks not_allowed)
				(vias allowed)
				(pads allowed)
				(copperpour not_allowed)
				(footprints allowed)
			)
			(placement
				(enabled no)
				(sheetname "")
			)
			(fill
				(thermal_gap 0.5)
				(thermal_bridge_width 0.5)
				(island_removal_mode 0)
			)
			(polygon
				(pts
					(xy 31.112968 -139.8016) (xy 31.112968 -140.3096) (xy 30.731968 -140.3096) (xy 30.731968 -139.8016)
				)
			)
		)
	)
)
